# BASEBOARD_FAB2 (Tioga Pass) — schematic netlist excerpt (pin names and nets, part order shuffled) for the footprints in the layout excerpt that follows; sources: Cadence DE-HDL packaged netlist, KiCad conversion of Wiwynn_Tioga_Pass_MB.brd

C2T27  CAP_A  0.01UF 25V 10% X7R  pkg 0402V  page 101 : A = P3V3_STBY_MNG_RGMII ; B = GND
C3P49  CAP_A  0.1UF 16V 10% X7R  pkg 0402V  page 92 : A = P0V7_GTL2104_VREF_1 ; B = GND
C5L1  CAP  100UF 4V 20% X5R  pkg 0805  page 220 : A = PVDDQ_DEF ; B = GND

(kicad_pcb
	(version 20260206)
	(generator "pcbnew")
	(generator_version "10.0")
	(general
		(thickness 1.6)
		(legacy_teardrops no)
	)
	(paper "A4")
	(title_block
		(title "Wiwynn_Tioga_Pass_MB.brd")
		(comment 1 "Tioga Pass / footprints 3863-3865 of 4770")
	)
	(layers
		(0 "F.Cu" signal "TOP")
		(4 "In1.Cu" signal "L2GND")
		(6 "In2.Cu" signal "L3")
		(8 "In3.Cu" signal "L4GND")
		(10 "In4.Cu" signal "L5")
		(12 "In5.Cu" signal "L6GND")
		(14 "In6.Cu" signal "L7VCC")
		(16 "In7.Cu" signal "L8VCC")
		(18 "In8.Cu" signal "L9GND")
		(20 "In9.Cu" signal "L10")
		(22 "In10.Cu" signal "L11GND")
		(24 "In11.Cu" signal "L12")
		(26 "In12.Cu" signal "L13GND")
		(2 "B.Cu" signal "BOTTOM")
		(9 "F.Adhes" user "F.Adhesive")
		(11 "B.Adhes" user "B.Adhesive")
		(13 "F.Paste" user "Package Geometry/Pastemask Top")
		(15 "B.Paste" user "Package Geometry/Pastemask Bottom")
		(5 "F.SilkS" user "Ref Des/Silkscreen Top")
		(7 "B.SilkS" user "Ref Des/Silkscreen Bottom")
		(1 "F.Mask" user "Board Geometry/Soldermask Top")
		(3 "B.Mask" user "Board Geometry/Soldermask Bottom")
		(17 "Dwgs.User" user "User.Drawings")
		(19 "Cmts.User" user "User.Comments")
		(21 "Eco1.User" user "User.Eco1")
		(23 "Eco2.User" user "User.Eco2")
		(25 "Edge.Cuts" user "Board Geometry/Outline")
		(27 "Margin" user)
		(31 "F.CrtYd" user "Package Geometry/Place Bound Top")
		(29 "B.CrtYd" user "Package Geometry/Place Bound Bottom")
		(35 "F.Fab" user "Ref Des/Assembly Top")
		(33 "B.Fab" user "Ref Des/Assembly Bottom")
	)
	(footprint ""
		(layer "B.Cu")
		(at 372.631716 -59.289442 180)
		(property "Reference" "C3P49"
			(at 0 0 0)
			(layer "B.SilkS")
			(hide yes)
			(effects
				(font
					(size 1.27 1.27)
				)
				(justify mirror)
			)
		)
		(property "Value" ""
			(at 0 0 0)
			(layer "B.Fab")
			(effects
				(font
					(size 1.27 1.27)
				)
				(justify mirror)
			)
		)
		(duplicate_pad_numbers_are_jumpers no)
		(fp_poly
			(pts
				(xy -0.3048 -0.1016) (xy -0.3048 0.9906) (xy 0.3048 0.9906) (xy 0.3048 -0.1016)
			)
			(stroke
				(width 0)
				(type default)
			)
			(fill no)
			(layer "B.CrtYd")
		)
		(fp_line
			(start 0.3048 0.9906)
			(end -0.3048 0.9906)
			(stroke
				(width 0.1)
				(type default)
			)
			(layer "B.Fab")
		)
		(fp_line
			(start 0.3048 -0.1016)
			(end 0.3048 0.9906)
			(stroke
				(width 0.1)
				(type default)
			)
			(layer "B.Fab")
		)
		(fp_line
			(start -0.3048 0.9906)
			(end -0.3048 -0.1016)
			(stroke
				(width 0.1)
				(type default)
			)
			(layer "B.Fab")
		)
		(fp_line
			(start -0.3048 -0.1016)
			(end 0.3048 -0.1016)
			(stroke
				(width 0.1)
				(type default)
			)
			(layer "B.Fab")
		)
		(pad "1" smd rect
			(at 0 0)
			(size 0.508 0.508)
			(layers "B.Cu" "B.Mask" "B.Paste")
			(net "P0V7_GTL2104_VREF_1")
		)
		(pad "2" smd rect
			(at 0 0.889)
			(size 0.508 0.508)
			(layers "B.Cu" "B.Mask" "B.Paste")
			(net "GND")
		)
		(zone
			(layer "B.Cu")
			(hatch none 0.5)
			(connect_pads
				(clearance 0)
			)
			(min_thickness 0.25)
			(keepout
				(tracks not_allowed)
				(vias allowed)
				(pads allowed)
				(copperpour not_allowed)
				(footprints allowed)
			)
			(placement
				(enabled no)
				(sheetname "")
			)
			(fill
				(thermal_gap 0.5)
				(thermal_bridge_width 0.5)
				(island_removal_mode 0)
			)
			(polygon
				(pts
					(xy 372.377716 -59.924442) (xy 372.885716 -59.924442) (xy 372.885716 -59.543442) (xy 372.377716 -59.543442)
				)
			)
		)
		(zone
			(layer "B.Cu")
			(hatch none 0.5)
			(connect_pads
				(clearance 0)
			)
			(min_thickness 0.25)
			(keepout
				(tracks allowed)
				(vias not_allowed)
				(pads allowed)
				(copperpour not_allowed)
				(footprints allowed)
			)
			(placement
				(enabled no)
				(sheetname "")
			)
			(fill
				(thermal_gap 0.5)
				(thermal_bridge_width 0.5)
				(island_removal_mode 0)
			)
			(polygon
				(pts
					(xy 372.377716 -59.543442) (xy 372.885716 -59.543442) (xy 372.885716 -59.924442) (xy 372.377716 -59.924442)
				)
			)
		)
	)
	(footprint ""
		(layer "B.Cu")
		(at 474.41866 -29.96692 90)
		(property "Reference" "C2T27"
			(at 0 0 90)
			(layer "B.SilkS")
			(hide yes)
			(effects
				(font
					(size 1.27 1.27)
				)
				(justify mirror)
			)
		)
		(property "Value" ""
			(at 0 0 90)
			(layer "B.Fab")
			(effects
				(font
					(size 1.27 1.27)
				)
				(justify mirror)
			)
		)
		(duplicate_pad_numbers_are_jumpers no)
		(fp_poly
			(pts
				(xy -0.3048 -0.1016) (xy -0.3048 0.9906) (xy 0.3048 0.9906) (xy 0.3048 -0.1016)
			)
			(stroke
				(width 0)
				(type default)
			)
			(fill no)
			(layer "B.CrtYd")
		)
		(fp_line
			(start 0.3048 -0.1016)
			(end 0.3048 0.9906)
			(stroke
				(width 0.1)
				(type default)
			)
			(layer "B.Fab")
		)
		(fp_line
			(start -0.3048 -0.1016)
			(end 0.3048 -0.1016)
			(stroke
				(width 0.1)
				(type default)
			)
			(layer "B.Fab")
		)
		(fp_line
			(start 0.3048 0.9906)
			(end -0.3048 0.9906)
			(stroke
				(width 0.1)
				(type default)
			)
			(layer "B.Fab")
		)
		(fp_line
			(start -0.3048 0.9906)
			(end -0.3048 -0.1016)
			(stroke
				(width 0.1)
				(type default)
			)
			(layer "B.Fab")
		)
		(pad "1" smd rect
			(at 0 0 270)
			(size 0.508 0.508)
			(layers "B.Cu" "B.Mask" "B.Paste")
			(net "P3V3_STBY_MNG_RGMII")
		)
		(pad "2" smd rect
			(at 0 0.889 270)
			(size 0.508 0.508)
			(layers "B.Cu" "B.Mask" "B.Paste")
			(net "GND")
		)
		(zone
			(layer "B.Cu")
			(hatch none 0.5)
			(connect_pads
				(clearance 0)
			)
			(min_thickness 0.25)
			(keepout
				(tracks allowed)
				(vias not_allowed)
				(pads allowed)
				(copperpour not_allowed)
				(footprints allowed)
			)
			(placement
				(enabled no)
				(sheetname "")
			)
			(fill
				(thermal_gap 0.5)
				(thermal_bridge_width 0.5)
				(island_removal_mode 0)
			)
			(polygon
				(pts
					(xy 474.67266 -30.22092) (xy 474.67266 -29.71292) (xy 475.05366 -29.71292) (xy 475.05366 -30.22092)
				)
			)
		)
		(zone
			(layer "B.Cu")
			(hatch none 0.5)
			(connect_pads
				(clearance 0)
			)
			(min_thickness 0.25)
			(keepout
				(tracks not_allowed)
				(vias allowed)
				(pads allowed)
				(copperpour not_allowed)
				(footprints allowed)
			)
			(placement
				(enabled no)
				(sheetname "")
			)
			(fill
				(thermal_gap 0.5)
				(thermal_bridge_width 0.5)
				(island_removal_mode 0)
			)
			(polygon
				(pts
					(xy 475.05366 -30.22092) (xy 475.05366 -29.71292) (xy 474.67266 -29.71292) (xy 474.67266 -30.22092)
				)
			)
		)
	)
	(footprint ""
		(layer "B.Cu")
		(at 276.487128 -156.960824 90)
		(property "Reference" "C5L1"
			(at 0 0 90)
			(layer "B.SilkS")
			(hide yes)
			(effects
				(font
					(size 1.27 1.27)
				)
				(justify mirror)
			)
		)
		(property "Value" ""
			(at 0 0 90)
			(layer "B.Fab")
			(effects
				(font
					(size 1.27 1.27)
				)
				(justify mirror)
			)
		)
		(duplicate_pad_numbers_are_jumpers no)
		(fp_rect
			(start 0.7239 1.9939)
			(end -0.7239 -0.2159)
			(stroke
				(width 0)
				(type default)
			)
			(fill no)
			(layer "B.CrtYd")
		)
		(fp_line
			(start 0.7239 -0.2159)
			(end 0.7239 1.9939)
			(stroke
				(width 0.1)
				(type default)
			)
			(layer "B.Fab")
		)
		(fp_line
			(start -0.7239 -0.2159)
			(end 0.7239 -0.2159)
			(stroke
				(width 0.1)
				(type default)
			)
			(layer "B.Fab")
		)
		(fp_line
			(start 0.7239 1.9939)
			(end -0.7239 1.9939)
			(stroke
				(width 0.1)
				(type default)
			)
			(layer "B.Fab")
		)
		(fp_line
			(start -0.7239 1.9939)
			(end -0.7239 -0.2159)
			(stroke
				(width 0.1)
				(type default)
			)
			(layer "B.Fab")
		)
		(pad "1" smd rect
			(at 0 0 270)
			(size 1.27 1.016)
			(layers "B.Cu" "B.Mask" "B.Paste")
			(net "PVDDQ_DEF")
		)
		(pad "2" smd rect
			(at 0 1.778 270)
			(size 1.27 1.016)
			(layers "B.Cu" "B.Mask" "B.Paste")
			(net "GND")
		)
		(zone
			(layer "B.Cu")
			(hatch none 0.5)
			(connect_pads
				(clearance 0)
			)
			(min_thickness 0.25)
			(keepout
				(tracks not_allowed)
				(vias allowed)
				(pads allowed)
				(copperpour not_allowed)
				(footprints allowed)
			)
			(placement
				(enabled no)
				(sheetname "")
			)
			(fill
				(thermal_gap 0.5)
				(thermal_bridge_width 0.5)
				(island_removal_mode 0)
			)
			(polygon
				(pts
					(xy 277.757128 -157.595824) (xy 276.995128 -157.595824) (xy 276.995128 -156.325824) (xy 277.757128 -156.325824)
				)
			)
		)
	)
)
